(kicad_pcb
	(version 20260206)
	(generator "pcbnew")
	(generator_version "10.0")
	(general
		(thickness 1.6)
		(legacy_teardrops no)
	)
	(paper "A4")
	(title_block
		(title "01162023_DA0F0TEBIF0_F0T_Expander_BD_F_brd_V02_OCP.brd")
		(comment 1 "Grand Teton / footprints 1329-1334 of 9728")
	)
	(layers
		(0 "F.Cu" signal "TOP")
		(4 "In1.Cu" signal "GND")
		(6 "In2.Cu" signal "VCC")
		(8 "In3.Cu" signal "VCC1")
		(10 "In4.Cu" signal "GND1")
		(12 "In5.Cu" signal "IN1")
		(14 "In6.Cu" signal "GND2")
		(16 "In7.Cu" signal "IN2")
		(18 "In8.Cu" signal "GND3")
		(20 "In9.Cu" signal "IN3")
		(22 "In10.Cu" signal "GND4")
		(24 "In11.Cu" signal "IN4")
		(26 "In12.Cu" signal "GND5")
		(28 "In13.Cu" signal "IN5")
		(30 "In14.Cu" signal "GND6")
		(32 "In15.Cu" signal "IN6")
		(34 "In16.Cu" signal "GND7")
		(2 "B.Cu" signal "BOTTOM")
		(9 "F.Adhes" user "F.Adhesive")
		(11 "B.Adhes" user "B.Adhesive")
		(13 "F.Paste" user "Package Geometry/Pastemask Top")
		(15 "B.Paste" user "Package Geometry/Pastemask Bottom")
		(5 "F.SilkS" user "Ref Des/Silkscreen Top")
		(7 "B.SilkS" user "Ref Des/Silkscreen Bottom")
		(1 "F.Mask" user "Board Geometry/Soldermask Top")
		(3 "B.Mask" user "Board Geometry/Soldermask Bottom")
		(17 "Dwgs.User" user "User.Drawings")
		(19 "Cmts.User" user "User.Comments")
		(21 "Eco1.User" user "User.Eco1")
		(23 "Eco2.User" user "User.Eco2")
		(25 "Edge.Cuts" user "Board Geometry/Outline")
		(27 "Margin" user)
		(31 "F.CrtYd" user "Package Geometry/Place Bound Top")
		(29 "B.CrtYd" user "Package Geometry/Place Bound Bottom")
		(35 "F.Fab" user "Ref Des/Assembly Top")
		(33 "B.Fab" user "Ref Des/Assembly Bottom")
	)
	(footprint ""
		(layer "F.Cu")
		(at 26.267918 -56.353456)
		(property "Reference" "C2861"
			(at 0 0 0)
			(layer "F.SilkS")
			(hide yes)
			(effects
				(font
					(size 1.27 1.27)
				)
			)
		)
		(property "Value" ""
			(at 0 0 0)
			(layer "F.Fab")
			(effects
				(font
					(size 1.27 1.27)
				)
			)
		)
		(duplicate_pad_numbers_are_jumpers no)
		(fp_line
			(start -0.7874 -0.4064)
			(end 0.7874 -0.4064)
			(stroke
				(width 0.1524)
				(type default)
			)
			(layer "F.SilkS")
		)
		(fp_line
			(start -0.7874 0.4064)
			(end -0.7874 -0.4064)
			(stroke
				(width 0.1524)
				(type default)
			)
			(layer "F.SilkS")
		)
		(fp_line
			(start 0.7874 -0.4064)
			(end 0.7874 0.4064)
			(stroke
				(width 0.1524)
				(type default)
			)
			(layer "F.SilkS")
		)
		(fp_line
			(start 0.7874 0.4064)
			(end -0.7874 0.4064)
			(stroke
				(width 0.1524)
				(type default)
			)
			(layer "F.SilkS")
		)
		(fp_line
			(start -0.67945 -0.305054)
			(end -0.12065 -0.305054)
			(stroke
				(width 0.1)
				(type default)
			)
			(layer "F.Fab")
		)
		(fp_line
			(start -0.67945 0.3048)
			(end -0.67945 -0.305054)
			(stroke
				(width 0.1)
				(type default)
			)
			(layer "F.Fab")
		)
		(fp_line
			(start -0.12065 -0.305054)
			(end -0.12065 -0.2794)
			(stroke
				(width 0.1)
				(type default)
			)
			(layer "F.Fab")
		)
		(fp_line
			(start -0.12065 -0.2794)
			(end 0.12065 -0.2794)
			(stroke
				(width 0.1)
				(type default)
			)
			(layer "F.Fab")
		)
		(fp_line
			(start -0.12065 0.2794)
			(end -0.12065 0.3048)
			(stroke
				(width 0.1)
				(type default)
			)
			(layer "F.Fab")
		)
		(fp_line
			(start -0.12065 0.3048)
			(end -0.67945 0.3048)
			(stroke
				(width 0.1)
				(type default)
			)
			(layer "F.Fab")
		)
		(fp_line
			(start 0.120396 0.2794)
			(end -0.12065 0.2794)
			(stroke
				(width 0.1)
				(type default)
			)
			(layer "F.Fab")
		)
		(fp_line
			(start 0.120396 0.3048)
			(end 0.120396 0.2794)
			(stroke
				(width 0.1)
				(type default)
			)
			(layer "F.Fab")
		)
		(fp_line
			(start 0.12065 -0.3048)
			(end 0.67945 -0.3048)
			(stroke
				(width 0.1)
				(type default)
			)
			(layer "F.Fab")
		)
		(fp_line
			(start 0.12065 -0.2794)
			(end 0.12065 -0.3048)
			(stroke
				(width 0.1)
				(type default)
			)
			(layer "F.Fab")
		)
		(fp_line
			(start 0.67945 -0.3048)
			(end 0.67945 0.3048)
			(stroke
				(width 0.1)
				(type default)
			)
			(layer "F.Fab")
		)
		(fp_line
			(start 0.67945 0.3048)
			(end 0.120396 0.3048)
			(stroke
				(width 0.1)
				(type default)
			)
			(layer "F.Fab")
		)
		(pad "1" smd circle
			(at -0.40005 0)
			(size 0 0)
			(layers "F.Cu" "F.Mask" "F.Paste")
			(net "SSD0_PWR_EN_R")
		)
		(pad "2" smd circle
			(at 0.40005 0)
			(size 0 0)
			(layers "F.Cu" "F.Mask" "F.Paste")
			(net "GND")
		)
	)
	(footprint ""
		(layer "F.Cu")
		(at 300.60519 -210.094068 -90)
		(property "Reference" "R3365"
			(at 0 0 270)
			(layer "F.SilkS")
			(hide yes)
			(effects
				(font
					(size 1.27 1.27)
				)
			)
		)
		(property "Value" ""
			(at 0 0 270)
			(layer "F.Fab")
			(effects
				(font
					(size 1.27 1.27)
				)
			)
		)
		(duplicate_pad_numbers_are_jumpers no)
		(fp_line
			(start -0.7874 0.4064)
			(end -0.7874 -0.4064)
			(stroke
				(width 0.1524)
				(type default)
			)
			(layer "F.SilkS")
		)
		(fp_line
			(start 0.7874 0.4064)
			(end -0.7874 0.4064)
			(stroke
				(width 0.1524)
				(type default)
			)
			(layer "F.SilkS")
		)
		(fp_line
			(start -0.7874 -0.4064)
			(end 0.7874 -0.4064)
			(stroke
				(width 0.1524)
				(type default)
			)
			(layer "F.SilkS")
		)
		(fp_line
			(start 0.7874 -0.4064)
			(end 0.7874 0.4064)
			(stroke
				(width 0.1524)
				(type default)
			)
			(layer "F.SilkS")
		)
		(fp_line
			(start -0.67945 0.3048)
			(end -0.67945 -0.305054)
			(stroke
				(width 0.1)
				(type default)
			)
			(layer "F.Fab")
		)
		(fp_line
			(start -0.12065 0.3048)
			(end -0.67945 0.3048)
			(stroke
				(width 0.1)
				(type default)
			)
			(layer "F.Fab")
		)
		(fp_line
			(start 0.120396 0.3048)
			(end 0.120396 0.2794)
			(stroke
				(width 0.1)
				(type default)
			)
			(layer "F.Fab")
		)
		(fp_line
			(start 0.67945 0.3048)
			(end 0.120396 0.3048)
			(stroke
				(width 0.1)
				(type default)
			)
			(layer "F.Fab")
		)
		(fp_line
			(start -0.12065 0.2794)
			(end -0.12065 0.3048)
			(stroke
				(width 0.1)
				(type default)
			)
			(layer "F.Fab")
		)
		(fp_line
			(start 0.120396 0.2794)
			(end -0.12065 0.2794)
			(stroke
				(width 0.1)
				(type default)
			)
			(layer "F.Fab")
		)
		(fp_line
			(start -0.12065 -0.2794)
			(end 0.12065 -0.2794)
			(stroke
				(width 0.1)
				(type default)
			)
			(layer "F.Fab")
		)
		(fp_line
			(start 0.12065 -0.2794)
			(end 0.12065 -0.3048)
			(stroke
				(width 0.1)
				(type default)
			)
			(layer "F.Fab")
		)
		(fp_line
			(start 0.12065 -0.3048)
			(end 0.67945 -0.3048)
			(stroke
				(width 0.1)
				(type default)
			)
			(layer "F.Fab")
		)
		(fp_line
			(start 0.67945 -0.3048)
			(end 0.67945 0.3048)
			(stroke
				(width 0.1)
				(type default)
			)
			(layer "F.Fab")
		)
		(fp_line
			(start -0.67945 -0.305054)
			(end -0.12065 -0.305054)
			(stroke
				(width 0.1)
				(type default)
			)
			(layer "F.Fab")
		)
		(fp_line
			(start -0.12065 -0.305054)
			(end -0.12065 -0.2794)
			(stroke
				(width 0.1)
				(type default)
			)
			(layer "F.Fab")
		)
		(pad "1" smd circle
			(at -0.40005 0 270)
			(size 0 0)
			(layers "F.Cu" "F.Mask" "F.Paste")
			(net "SPI_BIC1_CS0_LS23_R_N")
		)
		(pad "2" smd circle
			(at 0.40005 0 270)
			(size 0 0)
			(layers "F.Cu" "F.Mask" "F.Paste")
			(net "SPI_BIC1_CS0_LS23_N")
		)
	)
	(footprint ""
		(layer "F.Cu")
		(at 314.86602 -77.889608 180)
		(property "Reference" "C930"
			(at 0 0 180)
			(layer "F.SilkS")
			(hide yes)
			(effects
				(font
					(size 1.27 1.27)
				)
			)
		)
		(property "Value" ""
			(at 0 0 180)
			(layer "F.Fab")
			(effects
				(font
					(size 1.27 1.27)
				)
			)
		)
		(duplicate_pad_numbers_are_jumpers no)
		(fp_line
			(start 0.7874 0.4064)
			(end -0.7874 0.4064)
			(stroke
				(width 0.1524)
				(type default)
			)
			(layer "F.SilkS")
		)
		(fp_line
			(start 0.7874 -0.4064)
			(end 0.7874 0.4064)
			(stroke
				(width 0.1524)
				(type default)
			)
			(layer "F.SilkS")
		)
		(fp_line
			(start -0.7874 0.4064)
			(end -0.7874 -0.4064)
			(stroke
				(width 0.1524)
				(type default)
			)
			(layer "F.SilkS")
		)
		(fp_line
			(start -0.7874 -0.4064)
			(end 0.7874 -0.4064)
			(stroke
				(width 0.1524)
				(type default)
			)
			(layer "F.SilkS")
		)
		(fp_line
			(start 0.67945 0.3048)
			(end 0.120396 0.3048)
			(stroke
				(width 0.1)
				(type default)
			)
			(layer "F.Fab")
		)
		(fp_line
			(start 0.67945 -0.3048)
			(end 0.67945 0.3048)
			(stroke
				(width 0.1)
				(type default)
			)
			(layer "F.Fab")
		)
		(fp_line
			(start 0.12065 -0.2794)
			(end 0.12065 -0.3048)
			(stroke
				(width 0.1)
				(type default)
			)
			(layer "F.Fab")
		)
		(fp_line
			(start 0.12065 -0.3048)
			(end 0.67945 -0.3048)
			(stroke
				(width 0.1)
				(type default)
			)
			(layer "F.Fab")
		)
		(fp_line
			(start 0.120396 0.3048)
			(end 0.120396 0.2794)
			(stroke
				(width 0.1)
				(type default)
			)
			(layer "F.Fab")
		)
		(fp_line
			(start 0.120396 0.2794)
			(end -0.12065 0.2794)
			(stroke
				(width 0.1)
				(type default)
			)
			(layer "F.Fab")
		)
		(fp_line
			(start -0.12065 0.3048)
			(end -0.67945 0.3048)
			(stroke
				(width 0.1)
				(type default)
			)
			(layer "F.Fab")
		)
		(fp_line
			(start -0.12065 0.2794)
			(end -0.12065 0.3048)
			(stroke
				(width 0.1)
				(type default)
			)
			(layer "F.Fab")
		)
		(fp_line
			(start -0.12065 -0.2794)
			(end 0.12065 -0.2794)
			(stroke
				(width 0.1)
				(type default)
			)
			(layer "F.Fab")
		)
		(fp_line
			(start -0.12065 -0.305054)
			(end -0.12065 -0.2794)
			(stroke
				(width 0.1)
				(type default)
			)
			(layer "F.Fab")
		)
		(fp_line
			(start -0.67945 0.3048)
			(end -0.67945 -0.305054)
			(stroke
				(width 0.1)
				(type default)
			)
			(layer "F.Fab")
		)
		(fp_line
			(start -0.67945 -0.305054)
			(end -0.12065 -0.305054)
			(stroke
				(width 0.1)
				(type default)
			)
			(layer "F.Fab")
		)
		(pad "1" smd circle
			(at -0.40005 0 180)
			(size 0 0)
			(layers "F.Cu" "F.Mask" "F.Paste")
			(net "P3V3_NIC5")
		)
		(pad "2" smd circle
			(at 0.40005 0 180)
			(size 0 0)
			(layers "F.Cu" "F.Mask" "F.Paste")
			(net "GND")
		)
	)
	(footprint ""
		(layer "F.Cu")
		(at 29.88818 -257.64871 -90)
		(property "Reference" "C3019"
			(at 0 0 270)
			(layer "F.SilkS")
			(hide yes)
			(effects
				(font
					(size 1.27 1.27)
				)
			)
		)
		(property "Value" ""
			(at 0 0 270)
			(layer "F.Fab")
			(effects
				(font
					(size 1.27 1.27)
				)
			)
		)
		(duplicate_pad_numbers_are_jumpers no)
		(fp_line
			(start -1.2954 0.5842)
			(end -1.2954 -0.5842)
			(stroke
				(width 0.1524)
				(type default)
			)
			(layer "F.SilkS")
		)
		(fp_line
			(start 1.2954 0.5842)
			(end -1.2954 0.5842)
			(stroke
				(width 0.1524)
				(type default)
			)
			(layer "F.SilkS")
		)
		(fp_line
			(start -1.2954 -0.5842)
			(end 1.2954 -0.5842)
			(stroke
				(width 0.1524)
				(type default)
			)
			(layer "F.SilkS")
		)
		(fp_line
			(start 1.2954 -0.5842)
			(end 1.2954 0.5842)
			(stroke
				(width 0.1524)
				(type default)
			)
			(layer "F.SilkS")
		)
		(fp_line
			(start -0.8636 0.4572)
			(end -0.8636 0.4064)
			(stroke
				(width 0.1)
				(type default)
			)
			(layer "F.Fab")
		)
		(fp_line
			(start 0.8636 0.4572)
			(end -0.8636 0.4572)
			(stroke
				(width 0.1)
				(type default)
			)
			(layer "F.Fab")
		)
		(fp_line
			(start -1.1938 0.4064)
			(end -1.1938 -0.4064)
			(stroke
				(width 0.1)
				(type default)
			)
			(layer "F.Fab")
		)
		(fp_line
			(start -0.8636 0.4064)
			(end -1.1938 0.4064)
			(stroke
				(width 0.1)
				(type default)
			)
			(layer "F.Fab")
		)
		(fp_line
			(start 0.8636 0.4064)
			(end 0.8636 0.4572)
			(stroke
				(width 0.1)
				(type default)
			)
			(layer "F.Fab")
		)
		(fp_line
			(start 1.1938 0.4064)
			(end 0.8636 0.4064)
			(stroke
				(width 0.1)
				(type default)
			)
			(layer "F.Fab")
		)
		(fp_line
			(start -1.1938 -0.4064)
			(end -0.8636 -0.4064)
			(stroke
				(width 0.1)
				(type default)
			)
			(layer "F.Fab")
		)
		(fp_line
			(start -0.8636 -0.4064)
			(end -0.8636 -0.4572)
			(stroke
				(width 0.1)
				(type default)
			)
			(layer "F.Fab")
		)
		(fp_line
			(start 0.8636 -0.4064)
			(end 1.1938 -0.4064)
			(stroke
				(width 0.1)
				(type default)
			)
			(layer "F.Fab")
		)
		(fp_line
			(start 1.1938 -0.4064)
			(end 1.1938 0.4064)
			(stroke
				(width 0.1)
				(type default)
			)
			(layer "F.Fab")
		)
		(fp_line
			(start -0.8636 -0.4572)
			(end 0.8636 -0.4572)
			(stroke
				(width 0.1)
				(type default)
			)
			(layer "F.Fab")
		)
		(fp_line
			(start 0.8636 -0.4572)
			(end 0.8636 -0.4064)
			(stroke
				(width 0.1)
				(type default)
			)
			(layer "F.Fab")
		)
		(pad "1" smd rect
			(at -0.7366 0 180)
			(size 0.7112 0.8128)
			(layers "F.Cu" "F.Mask" "F.Paste")
			(net "P1V8_PLL0_PEX0")
		)
		(pad "2" smd rect
			(at 0.7366 0 180)
			(size 0.7112 0.8128)
			(layers "F.Cu" "F.Mask" "F.Paste")
			(net "GND")
		)
	)
	(footprint ""
		(layer "F.Cu")
		(at 30.153356 -288.190432)
		(property "Reference" "L94"
			(at 0 0 0)
			(layer "F.SilkS")
			(hide yes)
			(effects
				(font
					(size 1.27 1.27)
				)
			)
		)
		(property "Value" ""
			(at 0 0 0)
			(layer "F.Fab")
			(effects
				(font
					(size 1.27 1.27)
				)
			)
		)
		(duplicate_pad_numbers_are_jumpers no)
		(fp_line
			(start -1.63576 -0.8128)
			(end -1.63576 0.8128)
			(stroke
				(width 0.1524)
				(type default)
			)
			(layer "F.SilkS")
		)
		(fp_line
			(start -1.63576 -0.8128)
			(end 1.63576 -0.8128)
			(stroke
				(width 0.1524)
				(type default)
			)
			(layer "F.SilkS")
		)
		(fp_line
			(start 1.63576 -0.8128)
			(end 1.63576 0.8128)
			(stroke
				(width 0.1524)
				(type default)
			)
			(layer "F.SilkS")
		)
		(fp_line
			(start 1.63576 0.8128)
			(end -1.63576 0.8128)
			(stroke
				(width 0.1524)
				(type default)
			)
			(layer "F.SilkS")
		)
		(fp_line
			(start -1.56083 -0.738632)
			(end -1.56083 0.7366)
			(stroke
				(width 0.1)
				(type default)
			)
			(layer "F.Fab")
		)
		(fp_line
			(start -1.56083 0.7366)
			(end -1.524 0.7366)
			(stroke
				(width 0.1)
				(type default)
			)
			(layer "F.Fab")
		)
		(fp_line
			(start -1.524 0.7366)
			(end 1.524 0.7366)
			(stroke
				(width 0.1)
				(type default)
			)
			(layer "F.Fab")
		)
		(fp_line
			(start 1.524 0.7366)
			(end 1.560576 0.7366)
			(stroke
				(width 0.1)
				(type default)
			)
			(layer "F.Fab")
		)
		(fp_line
			(start 1.560576 -0.738632)
			(end -1.56083 -0.738632)
			(stroke
				(width 0.1)
				(type default)
			)
			(layer "F.Fab")
		)
		(fp_line
			(start 1.560576 0.7366)
			(end 1.560576 -0.738632)
			(stroke
				(width 0.1)
				(type default)
			)
			(layer "F.Fab")
		)
		(pad "1" smd rect
			(at -0.94996 0 180)
			(size 1.1176 1.3716)
			(layers "F.Cu" "F.Mask" "F.Paste")
			(net "P1V8_PLL0_PEX0")
		)
		(pad "2" smd rect
			(at 0.94996 0 180)
			(size 1.1176 1.3716)
			(layers "F.Cu" "F.Mask" "F.Paste")
			(net "PCEPLL6_VDDA18_PEX0")
		)
	)
	(footprint ""
		(layer "F.Cu")
		(at 279.14727 -20.35556)
		(property "Reference" "C3939"
			(at 0 0 0)
			(layer "F.SilkS")
			(hide yes)
			(effects
				(font
					(size 1.27 1.27)
				)
			)
		)
		(property "Value" ""
			(at 0 0 0)
			(layer "F.Fab")
			(effects
				(font
					(size 1.27 1.27)
				)
			)
		)
		(duplicate_pad_numbers_are_jumpers no)
		(fp_line
			(start -0.7874 -0.4064)
			(end 0.7874 -0.4064)
			(stroke
				(width 0.1524)
				(type default)
			)
			(layer "F.SilkS")
		)
		(fp_line
			(start -0.7874 0.4064)
			(end -0.7874 -0.4064)
			(stroke
				(width 0.1524)
				(type default)
			)
			(layer "F.SilkS")
		)
		(fp_line
			(start 0.7874 -0.4064)
			(end 0.7874 0.4064)
			(stroke
				(width 0.1524)
				(type default)
			)
			(layer "F.SilkS")
		)
		(fp_line
			(start 0.7874 0.4064)
			(end -0.7874 0.4064)
			(stroke
				(width 0.1524)
				(type default)
			)
			(layer "F.SilkS")
		)
		(fp_line
			(start -0.67945 -0.305054)
			(end -0.12065 -0.305054)
			(stroke
				(width 0.1)
				(type default)
			)
			(layer "F.Fab")
		)
		(fp_line
			(start -0.67945 0.3048)
			(end -0.67945 -0.305054)
			(stroke
				(width 0.1)
				(type default)
			)
			(layer "F.Fab")
		)
		(fp_line
			(start -0.12065 -0.305054)
			(end -0.12065 -0.2794)
			(stroke
				(width 0.1)
				(type default)
			)
			(layer "F.Fab")
		)
		(fp_line
			(start -0.12065 -0.2794)
			(end 0.12065 -0.2794)
			(stroke
				(width 0.1)
				(type default)
			)
			(layer "F.Fab")
		)
		(fp_line
			(start -0.12065 0.2794)
			(end -0.12065 0.3048)
			(stroke
				(width 0.1)
				(type default)
			)
			(layer "F.Fab")
		)
		(fp_line
			(start -0.12065 0.3048)
			(end -0.67945 0.3048)
			(stroke
				(width 0.1)
				(type default)
			)
			(layer "F.Fab")
		)
		(fp_line
			(start 0.120396 0.2794)
			(end -0.12065 0.2794)
			(stroke
				(width 0.1)
				(type default)
			)
			(layer "F.Fab")
		)
		(fp_line
			(start 0.120396 0.3048)
			(end 0.120396 0.2794)
			(stroke
				(width 0.1)
				(type default)
			)
			(layer "F.Fab")
		)
		(fp_line
			(start 0.12065 -0.3048)
			(end 0.67945 -0.3048)
			(stroke
				(width 0.1)
				(type default)
			)
			(layer "F.Fab")
		)
		(fp_line
			(start 0.12065 -0.2794)
			(end 0.12065 -0.3048)
			(stroke
				(width 0.1)
				(type default)
			)
			(layer "F.Fab")
		)
		(fp_line
			(start 0.67945 -0.3048)
			(end 0.67945 0.3048)
			(stroke
				(width 0.1)
				(type default)
			)
			(layer "F.Fab")
		)
		(fp_line
			(start 0.67945 0.3048)
			(end 0.120396 0.3048)
			(stroke
				(width 0.1)
				(type default)
			)
			(layer "F.Fab")
		)
		(pad "1" smd circle
			(at -0.40005 0)
			(size 0 0)
			(layers "F.Cu" "F.Mask" "F.Paste")
			(net "P12V_SSD9")
		)
		(pad "2" smd circle
			(at 0.40005 0)
			(size 0 0)
			(layers "F.Cu" "F.Mask" "F.Paste")
			(net "GND")
		)
	)
)
